# TIMECARD (Time Appliance Project (Time Card)) — schematic netlist excerpt (pin names and nets, part order shuffled) for the footprints in the layout excerpt that follows; sources: Cadence DE-HDL packaged netlist, KiCad conversion of R4006-B0001-02_R01.brd

R70  RESISTOR  4.7KOHM 1%  pkg SMC_0402R_H016  page 19 : \1\ = XP1R8V_ICP10100 ; \2\ = BF_ICP10100_I2C_SDA
C37  CAPACITOR  0.1UF 10V 10%  pkg SMC_0402R_H022  page 9 : \1\ = XP3R3V_FPGA ; \2\ = SG
TP43  TP_PIONT  pkg TP010CT020B030_PTH  page 25 : \1\ = XP12R0V_A_EN

(kicad_pcb
	(version 20260206)
	(generator "pcbnew")
	(generator_version "10.0")
	(general
		(thickness 1.6)
		(legacy_teardrops no)
	)
	(paper "A4")
	(title_block
		(title "timecard-production-celestica-r4006 — R4006-B0001-02_R01.brd")
		(comment 1 "Time Appliance Project (Time Card) / footprints 204-206 of 1113")
	)
	(layers
		(0 "F.Cu" signal "TOP")
		(4 "In1.Cu" signal "L02_GND1")
		(6 "In2.Cu" signal "L03_SIG1")
		(8 "In3.Cu" signal "L04_GND2")
		(10 "In4.Cu" signal "L05_VCC1")
		(12 "In5.Cu" signal "L06_VCC2")
		(14 "In6.Cu" signal "L07_GND3")
		(16 "In7.Cu" signal "L08_SIG2")
		(18 "In8.Cu" signal "L09_GND4")
		(2 "B.Cu" signal "BOTTOM")
		(9 "F.Adhes" user "F.Adhesive")
		(11 "B.Adhes" user "B.Adhesive")
		(13 "F.Paste" user "Package Geometry/Pastemask Top")
		(15 "B.Paste" user "Package Geometry/Pastemask Bottom")
		(5 "F.SilkS" user "Ref Des/Silkscreen Top")
		(7 "B.SilkS" user "Ref Des/Silkscreen Bottom")
		(1 "F.Mask" user "Board Geometry/Soldermask Top")
		(3 "B.Mask" user "Board Geometry/Soldermask Bottom")
		(17 "Dwgs.User" user "User.Drawings")
		(19 "Cmts.User" user "User.Comments")
		(21 "Eco1.User" user "User.Eco1")
		(23 "Eco2.User" user "User.Eco2")
		(25 "Edge.Cuts" user "Board Geometry/Outline")
		(27 "Margin" user)
		(31 "F.CrtYd" user "Package Geometry/Place Bound Top")
		(29 "B.CrtYd" user "Package Geometry/Place Bound Bottom")
		(35 "F.Fab" user "Ref Des/Assembly Top")
		(33 "B.Fab" user "Ref Des/Assembly Bottom")
	)
	(footprint ""
		(layer "F.Cu")
		(at 16.852392 -68.8086 180)
		(property "Reference" "R70"
			(at 1.993392 0.24765 0)
			(unlocked yes)
			(layer "F.SilkS")
			(effects
				(font
					(size 0.635 0.4064)
					(thickness 0.1524)
				)
			)
		)
		(property "Value" "VAL*"
			(at 0.02032 2.13233 180)
			(unlocked yes)
			(layer "F.Fab")
			(hide yes)
			(effects
				(font
					(size 0.7874 0.5842)
					(thickness 0.1524)
				)
			)
		)
		(property "Tolerance" "TOL*"
			(at 0.044704 3.05435 180)
			(unlocked yes)
			(layer "Cmts.User")
			(hide yes)
			(effects
				(font
					(size 0.7874 0.5842)
					(thickness 0.1524)
				)
			)
		)
		(property "User Part Number" "PARTNUM*"
			(at 0.02032 4.024884 180)
			(unlocked yes)
			(layer "Cmts.User")
			(hide yes)
			(effects
				(font
					(size 0.7874 0.5842)
					(thickness 0.1524)
				)
			)
		)
		(property "Device Type" "RESISTOR-G155-14701-01,4.7KOHMA"
			(at 0.008382 1.210564 180)
			(unlocked yes)
			(layer "F.Fab")
			(hide yes)
			(effects
				(font
					(size 0.7874 0.5842)
					(thickness 0.1524)
				)
			)
		)
		(duplicate_pad_numbers_are_jumpers no)
		(fp_line
			(start 1.143 0.5588)
			(end 1.143 -0.5588)
			(stroke
				(width 0.1)
				(type default)
			)
			(layer "F.SilkS")
		)
		(fp_line
			(start 1.143 -0.5588)
			(end -1.143 -0.5588)
			(stroke
				(width 0.1)
				(type default)
			)
			(layer "F.SilkS")
		)
		(fp_line
			(start -1.143 0.5588)
			(end 1.143 0.5588)
			(stroke
				(width 0.1)
				(type default)
			)
			(layer "F.SilkS")
		)
		(fp_line
			(start -1.143 -0.5588)
			(end -1.143 0.5588)
			(stroke
				(width 0.1)
				(type default)
			)
			(layer "F.SilkS")
		)
		(fp_rect
			(start 1.143 0.5588)
			(end -1.143 -0.5588)
			(stroke
				(width 0)
				(type default)
			)
			(fill no)
			(layer "F.CrtYd")
		)
		(fp_line
			(start 0.508 0.3048)
			(end 0.508 -0.3048)
			(stroke
				(width 0.1)
				(type default)
			)
			(layer "F.Fab")
		)
		(fp_line
			(start 0.508 -0.3048)
			(end -0.508 -0.3048)
			(stroke
				(width 0.1)
				(type default)
			)
			(layer "F.Fab")
		)
		(fp_line
			(start -0.508 0.3048)
			(end 0.508 0.3048)
			(stroke
				(width 0.1)
				(type default)
			)
			(layer "F.Fab")
		)
		(fp_line
			(start -0.508 -0.3048)
			(end -0.508 0.3048)
			(stroke
				(width 0.1)
				(type default)
			)
			(layer "F.Fab")
		)
		(pad "1" smd rect
			(at -0.5334 0 180)
			(size 0.7112 0.6096)
			(layers "F.Cu" "F.Mask" "F.Paste")
			(net "XP1R8V_ICP10100")
		)
		(pad "2" smd rect
			(at 0.5334 0 180)
			(size 0.7112 0.6096)
			(layers "F.Cu" "F.Mask" "F.Paste")
			(net "BF_ICP10100_I2C_SDA")
		)
		(zone
			(layer "F.Cu")
			(hatch none 0.5)
			(connect_pads
				(clearance 0)
			)
			(min_thickness 0.25)
			(keepout
				(tracks allowed)
				(vias not_allowed)
				(pads allowed)
				(copperpour not_allowed)
				(footprints allowed)
			)
			(placement
				(enabled no)
				(sheetname "")
			)
			(fill
				(thermal_gap 0.5)
				(thermal_bridge_width 0.5)
				(island_removal_mode 0)
			)
			(polygon
				(pts
					(xy 16.776192 -69.1134) (xy 16.776192 -68.5038) (xy 16.928592 -68.5038) (xy 16.928592 -69.1134)
				)
			)
		)
	)
	(footprint ""
		(layer "F.Cu")
		(at 75.59548 -16.96212)
		(property "Reference" "C37"
			(at 0.35052 -2.81051 0)
			(unlocked yes)
			(layer "F.SilkS")
			(effects
				(font
					(size 0.7874 0.5842)
					(thickness 0.1524)
				)
			)
		)
		(property "Value" "VAL*"
			(at 0.0762 2.067306 0)
			(unlocked yes)
			(layer "F.Fab")
			(hide yes)
			(effects
				(font
					(size 0.7874 0.5842)
					(thickness 0.1524)
				)
			)
		)
		(property "Tolerance" "TOL*"
			(at 0.0762 3.032506 0)
			(unlocked yes)
			(layer "Cmts.User")
			(hide yes)
			(effects
				(font
					(size 0.7874 0.5842)
					(thickness 0.1524)
				)
			)
		)
		(property "User Part Number" "PARTNUM*"
			(at 0.1016 4.023106 0)
			(unlocked yes)
			(layer "Cmts.User")
			(hide yes)
			(effects
				(font
					(size 0.7874 0.5842)
					(thickness 0.1524)
				)
			)
		)
		(property "Device Type" "CAPACITOR-G105-0B104-CK,0.1UF,A"
			(at 0.0508 1.127506 0)
			(unlocked yes)
			(layer "F.Fab")
			(hide yes)
			(effects
				(font
					(size 0.7874 0.5842)
					(thickness 0.1524)
				)
			)
		)
		(duplicate_pad_numbers_are_jumpers no)
		(fp_line
			(start -1.143 -0.5588)
			(end -1.143 0.5588)
			(stroke
				(width 0.1)
				(type default)
			)
			(layer "F.SilkS")
		)
		(fp_line
			(start -1.143 0.5588)
			(end 1.143 0.5588)
			(stroke
				(width 0.1)
				(type default)
			)
			(layer "F.SilkS")
		)
		(fp_line
			(start 1.143 -0.5588)
			(end -1.143 -0.5588)
			(stroke
				(width 0.1)
				(type default)
			)
			(layer "F.SilkS")
		)
		(fp_line
			(start 1.143 0.5588)
			(end 1.143 -0.5588)
			(stroke
				(width 0.1)
				(type default)
			)
			(layer "F.SilkS")
		)
		(fp_rect
			(start -1.143 0.5588)
			(end 1.143 -0.5588)
			(stroke
				(width 0)
				(type default)
			)
			(fill no)
			(layer "F.CrtYd")
		)
		(fp_line
			(start -0.508 -0.3048)
			(end -0.508 0.3048)
			(stroke
				(width 0.1)
				(type default)
			)
			(layer "F.Fab")
		)
		(fp_line
			(start -0.508 0.3048)
			(end 0.508 0.3048)
			(stroke
				(width 0.1)
				(type default)
			)
			(layer "F.Fab")
		)
		(fp_line
			(start 0.508 -0.3048)
			(end -0.508 -0.3048)
			(stroke
				(width 0.1)
				(type default)
			)
			(layer "F.Fab")
		)
		(fp_line
			(start 0.508 0.3048)
			(end 0.508 -0.3048)
			(stroke
				(width 0.1)
				(type default)
			)
			(layer "F.Fab")
		)
		(pad "1" smd rect
			(at -0.5334 0)
			(size 0.7112 0.6096)
			(layers "F.Cu" "F.Mask" "F.Paste")
			(net "XP3R3V_FPGA")
		)
		(pad "2" smd rect
			(at 0.5334 0)
			(size 0.7112 0.6096)
			(layers "F.Cu" "F.Mask" "F.Paste")
			(net "SG")
		)
		(zone
			(layer "F.Cu")
			(hatch none 0.5)
			(connect_pads
				(clearance 0)
			)
			(min_thickness 0.25)
			(keepout
				(tracks allowed)
				(vias not_allowed)
				(pads allowed)
				(copperpour not_allowed)
				(footprints allowed)
			)
			(placement
				(enabled no)
				(sheetname "")
			)
			(fill
				(thermal_gap 0.5)
				(thermal_bridge_width 0.5)
				(island_removal_mode 0)
			)
			(polygon
				(pts
					(xy 75.51928 -16.65732) (xy 75.67168 -16.65732) (xy 75.67168 -17.26692) (xy 75.51928 -17.26692)
				)
			)
		)
	)
	(footprint ""
		(layer "F.Cu")
		(at 143.764 -88.138)
		(property "Reference" "TP43"
			(at -3.8862 -0.08763 0)
			(unlocked yes)
			(layer "F.SilkS")
			(effects
				(font
					(size 0.7874 0.5842)
					(thickness 0.1524)
				)
				(justify left)
			)
		)
		(property "Value" ""
			(at 0 0 0)
			(layer "F.Fab")
			(effects
				(font
					(size 1.27 1.27)
				)
			)
		)
		(property "Device Type" "TP_PIONT-TP010CT020B030_PTH-TPA"
			(at -1.341882 0.996696 0)
			(unlocked yes)
			(layer "F.Fab")
			(hide yes)
			(effects
				(font
					(size 0.7874 0.5842)
					(thickness 0.000001)
				)
				(justify left)
			)
		)
		(duplicate_pad_numbers_are_jumpers no)
		(fp_poly
			(pts
				(arc
					(start 0.889 0)
					(mid -0.889 0)
					(end 0.889 0)
				)
			)
			(stroke
				(width 0)
				(type default)
			)
			(fill no)
			(layer "B.CrtYd")
		)
		(fp_poly
			(pts
				(arc
					(start 0.889 0)
					(mid -0.889 0)
					(end 0.889 0)
				)
			)
			(stroke
				(width 0)
				(type default)
			)
			(fill no)
			(layer "F.CrtYd")
		)
		(pad "1" thru_hole circle
			(at 0 0)
			(size 0.508 0.508)
			(drill 0.254)
			(layers "*.Cu" "*.Mask")
			(remove_unused_layers no)
			(net "XP12R0V_A_EN")
			(clearance 0.1016)
			(padstack
				(mode front_inner_back)
				(layer "Inner"
					(shape circle)
					(size 0.508 0.508)
					(clearance 0.1016)
				)
				(layer "B.Cu"
					(shape circle)
					(size 0.762 0.762)
					(clearance -0.0254)
				)
			)
		)
	)
)
